(kicad_pcb
	(version 20260206)
	(generator "pcbnew")
	(generator_version "10.0")
	(general
		(thickness 1.6)
		(legacy_teardrops no)
	)
	(paper "A4")
	(title_block
		(title "04192023_DAF0TMB3IC0_F0TG_MB_C_brd_V02_OCP.brd")
		(comment 1 "Grand Teton / footprints 6226-6231 of 8354")
	)
	(layers
		(0 "F.Cu" signal "TOP")
		(4 "In1.Cu" signal "GND")
		(6 "In2.Cu" signal "IN1")
		(8 "In3.Cu" signal "GND1")
		(10 "In4.Cu" signal "IN2")
		(12 "In5.Cu" signal "GND2")
		(14 "In6.Cu" signal "IN3")
		(16 "In7.Cu" signal "GND3")
		(18 "In8.Cu" signal "VCC")
		(20 "In9.Cu" signal "VCC1")
		(22 "In10.Cu" signal "GND4")
		(24 "In11.Cu" signal "IN4")
		(26 "In12.Cu" signal "GND5")
		(28 "In13.Cu" signal "IN5")
		(30 "In14.Cu" signal "GND6")
		(32 "In15.Cu" signal "IN6")
		(34 "In16.Cu" signal "GND7")
		(2 "B.Cu" signal "BOTTOM")
		(9 "F.Adhes" user "F.Adhesive")
		(11 "B.Adhes" user "B.Adhesive")
		(13 "F.Paste" user "Package Geometry/Pastemask Top")
		(15 "B.Paste" user "Package Geometry/Pastemask Bottom")
		(5 "F.SilkS" user "Ref Des/Silkscreen Top")
		(7 "B.SilkS" user "Ref Des/Silkscreen Bottom")
		(1 "F.Mask" user "Board Geometry/Soldermask Top")
		(3 "B.Mask" user "Board Geometry/Soldermask Bottom")
		(17 "Dwgs.User" user "User.Drawings")
		(19 "Cmts.User" user "User.Comments")
		(21 "Eco1.User" user "User.Eco1")
		(23 "Eco2.User" user "User.Eco2")
		(25 "Edge.Cuts" user "Board Geometry/Outline")
		(27 "Margin" user)
		(31 "F.CrtYd" user "Package Geometry/Place Bound Top")
		(29 "B.CrtYd" user "Package Geometry/Place Bound Bottom")
		(35 "F.Fab" user "Ref Des/Assembly Top")
		(33 "B.Fab" user "Ref Des/Assembly Bottom")
	)
	(footprint ""
		(layer "B.Cu")
		(at 47.417228 -337.989672 -90)
		(property "Reference" "PC459_1"
			(at 0 0 90)
			(layer "B.SilkS")
			(hide yes)
			(effects
				(font
					(size 1.27 1.27)
				)
				(justify mirror)
			)
		)
		(property "Value" ""
			(at 0 0 90)
			(layer "B.Fab")
			(effects
				(font
					(size 1.27 1.27)
				)
				(justify mirror)
			)
		)
		(duplicate_pad_numbers_are_jumpers no)
		(fp_line
			(start -1.524 0.762)
			(end 1.524 0.762)
			(stroke
				(width 0.1524)
				(type default)
			)
			(layer "B.SilkS")
		)
		(fp_line
			(start 1.524 0.762)
			(end 1.524 -0.762)
			(stroke
				(width 0.1524)
				(type default)
			)
			(layer "B.SilkS")
		)
		(fp_line
			(start -1.524 -0.762)
			(end -1.524 0.762)
			(stroke
				(width 0.1524)
				(type default)
			)
			(layer "B.SilkS")
		)
		(fp_line
			(start 1.524 -0.762)
			(end -1.524 -0.762)
			(stroke
				(width 0.1524)
				(type default)
			)
			(layer "B.SilkS")
		)
		(fp_line
			(start -1.1049 0.724916)
			(end -1.1049 -0.724916)
			(stroke
				(width 0.1)
				(type default)
			)
			(layer "B.Fab")
		)
		(fp_line
			(start 1.1049 0.724916)
			(end -1.1049 0.724916)
			(stroke
				(width 0.1)
				(type default)
			)
			(layer "B.Fab")
		)
		(fp_line
			(start -1.1049 -0.724916)
			(end 1.1049 -0.724916)
			(stroke
				(width 0.1)
				(type default)
			)
			(layer "B.Fab")
		)
		(fp_line
			(start 1.1049 -0.724916)
			(end 1.1049 0.724916)
			(stroke
				(width 0.1)
				(type default)
			)
			(layer "B.Fab")
		)
		(pad "1" smd rect
			(at 0.889 0 270)
			(size 1.016 1.27)
			(layers "B.Cu" "B.Mask" "B.Paste")
			(net "PVDDIO_P1")
		)
		(pad "2" smd rect
			(at -0.889 0 270)
			(size 1.016 1.27)
			(layers "B.Cu" "B.Mask" "B.Paste")
			(net "GND")
		)
	)
	(footprint ""
		(layer "B.Cu")
		(at 184.687972 -428.15764)
		(property "Reference" "R8110"
			(at 0 0 0)
			(layer "B.SilkS")
			(hide yes)
			(effects
				(font
					(size 1.27 1.27)
				)
				(justify mirror)
			)
		)
		(property "Value" ""
			(at 0 0 0)
			(layer "B.Fab")
			(effects
				(font
					(size 1.27 1.27)
				)
				(justify mirror)
			)
		)
		(duplicate_pad_numbers_are_jumpers no)
		(fp_line
			(start -0.7874 -0.4064)
			(end -0.7874 0.4064)
			(stroke
				(width 0.1524)
				(type default)
			)
			(layer "B.SilkS")
		)
		(fp_line
			(start -0.7874 0.4064)
			(end 0.7874 0.4064)
			(stroke
				(width 0.1524)
				(type default)
			)
			(layer "B.SilkS")
		)
		(fp_line
			(start 0.7874 -0.4064)
			(end -0.7874 -0.4064)
			(stroke
				(width 0.1524)
				(type default)
			)
			(layer "B.SilkS")
		)
		(fp_line
			(start 0.7874 0.4064)
			(end 0.7874 -0.4064)
			(stroke
				(width 0.1524)
				(type default)
			)
			(layer "B.SilkS")
		)
		(fp_line
			(start -0.67945 -0.3048)
			(end -0.67945 0.3048)
			(stroke
				(width 0.1)
				(type default)
			)
			(layer "B.Fab")
		)
		(fp_line
			(start -0.67945 0.3048)
			(end -0.120396 0.3048)
			(stroke
				(width 0.1)
				(type default)
			)
			(layer "B.Fab")
		)
		(fp_line
			(start -0.12065 -0.3048)
			(end -0.67945 -0.3048)
			(stroke
				(width 0.1)
				(type default)
			)
			(layer "B.Fab")
		)
		(fp_line
			(start -0.12065 -0.2794)
			(end -0.12065 -0.3048)
			(stroke
				(width 0.1)
				(type default)
			)
			(layer "B.Fab")
		)
		(fp_line
			(start -0.120396 0.2794)
			(end 0.12065 0.2794)
			(stroke
				(width 0.1)
				(type default)
			)
			(layer "B.Fab")
		)
		(fp_line
			(start -0.120396 0.3048)
			(end -0.120396 0.2794)
			(stroke
				(width 0.1)
				(type default)
			)
			(layer "B.Fab")
		)
		(fp_line
			(start 0.12065 -0.305054)
			(end 0.12065 -0.2794)
			(stroke
				(width 0.1)
				(type default)
			)
			(layer "B.Fab")
		)
		(fp_line
			(start 0.12065 -0.2794)
			(end -0.12065 -0.2794)
			(stroke
				(width 0.1)
				(type default)
			)
			(layer "B.Fab")
		)
		(fp_line
			(start 0.12065 0.2794)
			(end 0.12065 0.3048)
			(stroke
				(width 0.1)
				(type default)
			)
			(layer "B.Fab")
		)
		(fp_line
			(start 0.12065 0.3048)
			(end 0.67945 0.3048)
			(stroke
				(width 0.1)
				(type default)
			)
			(layer "B.Fab")
		)
		(fp_line
			(start 0.67945 -0.305054)
			(end 0.12065 -0.305054)
			(stroke
				(width 0.1)
				(type default)
			)
			(layer "B.Fab")
		)
		(fp_line
			(start 0.67945 0.3048)
			(end 0.67945 -0.305054)
			(stroke
				(width 0.1)
				(type default)
			)
			(layer "B.Fab")
		)
		(pad "1" smd circle
			(at 0.40005 0 180)
			(size 0 0)
			(layers "B.Cu" "B.Mask" "B.Paste")
			(net "HSC_D_OC_R2")
		)
		(pad "2" smd circle
			(at -0.40005 0 180)
			(size 0 0)
			(layers "B.Cu" "B.Mask" "B.Paste")
			(net "A_HSC_LOW_GATE")
		)
	)
	(footprint ""
		(layer "B.Cu")
		(at 344.318844 -398.942052 90)
		(property "Reference" "C594"
			(at 0 0 90)
			(layer "B.SilkS")
			(hide yes)
			(effects
				(font
					(size 1.27 1.27)
				)
				(justify mirror)
			)
		)
		(property "Value" ""
			(at 0 0 90)
			(layer "B.Fab")
			(effects
				(font
					(size 1.27 1.27)
				)
				(justify mirror)
			)
		)
		(duplicate_pad_numbers_are_jumpers no)
		(fp_line
			(start 0.7874 -0.4064)
			(end -0.7874 -0.4064)
			(stroke
				(width 0.1524)
				(type default)
			)
			(layer "B.SilkS")
		)
		(fp_line
			(start -0.7874 -0.4064)
			(end -0.7874 0.4064)
			(stroke
				(width 0.1524)
				(type default)
			)
			(layer "B.SilkS")
		)
		(fp_line
			(start 0.7874 0.4064)
			(end 0.7874 -0.4064)
			(stroke
				(width 0.1524)
				(type default)
			)
			(layer "B.SilkS")
		)
		(fp_line
			(start -0.7874 0.4064)
			(end 0.7874 0.4064)
			(stroke
				(width 0.1524)
				(type default)
			)
			(layer "B.SilkS")
		)
		(fp_line
			(start 0.67945 -0.305054)
			(end 0.12065 -0.305054)
			(stroke
				(width 0.1)
				(type default)
			)
			(layer "B.Fab")
		)
		(fp_line
			(start 0.12065 -0.305054)
			(end 0.12065 -0.2794)
			(stroke
				(width 0.1)
				(type default)
			)
			(layer "B.Fab")
		)
		(fp_line
			(start -0.12065 -0.3048)
			(end -0.67945 -0.3048)
			(stroke
				(width 0.1)
				(type default)
			)
			(layer "B.Fab")
		)
		(fp_line
			(start -0.67945 -0.3048)
			(end -0.67945 0.3048)
			(stroke
				(width 0.1)
				(type default)
			)
			(layer "B.Fab")
		)
		(fp_line
			(start 0.12065 -0.2794)
			(end -0.12065 -0.2794)
			(stroke
				(width 0.1)
				(type default)
			)
			(layer "B.Fab")
		)
		(fp_line
			(start -0.12065 -0.2794)
			(end -0.12065 -0.3048)
			(stroke
				(width 0.1)
				(type default)
			)
			(layer "B.Fab")
		)
		(fp_line
			(start 0.12065 0.2794)
			(end 0.12065 0.3048)
			(stroke
				(width 0.1)
				(type default)
			)
			(layer "B.Fab")
		)
		(fp_line
			(start -0.120396 0.2794)
			(end 0.12065 0.2794)
			(stroke
				(width 0.1)
				(type default)
			)
			(layer "B.Fab")
		)
		(fp_line
			(start 0.67945 0.3048)
			(end 0.67945 -0.305054)
			(stroke
				(width 0.1)
				(type default)
			)
			(layer "B.Fab")
		)
		(fp_line
			(start 0.12065 0.3048)
			(end 0.67945 0.3048)
			(stroke
				(width 0.1)
				(type default)
			)
			(layer "B.Fab")
		)
		(fp_line
			(start -0.120396 0.3048)
			(end -0.120396 0.2794)
			(stroke
				(width 0.1)
				(type default)
			)
			(layer "B.Fab")
		)
		(fp_line
			(start -0.67945 0.3048)
			(end -0.120396 0.3048)
			(stroke
				(width 0.1)
				(type default)
			)
			(layer "B.Fab")
		)
		(pad "1" smd circle
			(at 0.40005 0 270)
			(size 0 0)
			(layers "B.Cu" "B.Mask" "B.Paste")
			(net "P1V8_CPU0_RT1_1A")
		)
		(pad "2" smd circle
			(at -0.40005 0 270)
			(size 0 0)
			(layers "B.Cu" "B.Mask" "B.Paste")
			(net "GND")
		)
	)
	(footprint ""
		(layer "B.Cu")
		(at 231.114092 -321.775582)
		(property "Reference" "R1263"
			(at 0 0 0)
			(layer "B.SilkS")
			(hide yes)
			(effects
				(font
					(size 1.27 1.27)
				)
				(justify mirror)
			)
		)
		(property "Value" ""
			(at 0 0 0)
			(layer "B.Fab")
			(effects
				(font
					(size 1.27 1.27)
				)
				(justify mirror)
			)
		)
		(duplicate_pad_numbers_are_jumpers no)
		(fp_line
			(start -0.7874 -0.4064)
			(end -0.7874 0.4064)
			(stroke
				(width 0.1524)
				(type default)
			)
			(layer "B.SilkS")
		)
		(fp_line
			(start -0.7874 0.4064)
			(end 0.7874 0.4064)
			(stroke
				(width 0.1524)
				(type default)
			)
			(layer "B.SilkS")
		)
		(fp_line
			(start 0.7874 -0.4064)
			(end -0.7874 -0.4064)
			(stroke
				(width 0.1524)
				(type default)
			)
			(layer "B.SilkS")
		)
		(fp_line
			(start 0.7874 0.4064)
			(end 0.7874 -0.4064)
			(stroke
				(width 0.1524)
				(type default)
			)
			(layer "B.SilkS")
		)
		(fp_line
			(start -0.67945 -0.3048)
			(end -0.67945 0.3048)
			(stroke
				(width 0.1)
				(type default)
			)
			(layer "B.Fab")
		)
		(fp_line
			(start -0.67945 0.3048)
			(end -0.120396 0.3048)
			(stroke
				(width 0.1)
				(type default)
			)
			(layer "B.Fab")
		)
		(fp_line
			(start -0.12065 -0.3048)
			(end -0.67945 -0.3048)
			(stroke
				(width 0.1)
				(type default)
			)
			(layer "B.Fab")
		)
		(fp_line
			(start -0.12065 -0.2794)
			(end -0.12065 -0.3048)
			(stroke
				(width 0.1)
				(type default)
			)
			(layer "B.Fab")
		)
		(fp_line
			(start -0.120396 0.2794)
			(end 0.12065 0.2794)
			(stroke
				(width 0.1)
				(type default)
			)
			(layer "B.Fab")
		)
		(fp_line
			(start -0.120396 0.3048)
			(end -0.120396 0.2794)
			(stroke
				(width 0.1)
				(type default)
			)
			(layer "B.Fab")
		)
		(fp_line
			(start 0.12065 -0.305054)
			(end 0.12065 -0.2794)
			(stroke
				(width 0.1)
				(type default)
			)
			(layer "B.Fab")
		)
		(fp_line
			(start 0.12065 -0.2794)
			(end -0.12065 -0.2794)
			(stroke
				(width 0.1)
				(type default)
			)
			(layer "B.Fab")
		)
		(fp_line
			(start 0.12065 0.2794)
			(end 0.12065 0.3048)
			(stroke
				(width 0.1)
				(type default)
			)
			(layer "B.Fab")
		)
		(fp_line
			(start 0.12065 0.3048)
			(end 0.67945 0.3048)
			(stroke
				(width 0.1)
				(type default)
			)
			(layer "B.Fab")
		)
		(fp_line
			(start 0.67945 -0.305054)
			(end 0.12065 -0.305054)
			(stroke
				(width 0.1)
				(type default)
			)
			(layer "B.Fab")
		)
		(fp_line
			(start 0.67945 0.3048)
			(end 0.67945 -0.305054)
			(stroke
				(width 0.1)
				(type default)
			)
			(layer "B.Fab")
		)
		(pad "1" smd rect
			(at 0.40005 0)
			(size 0.4572 0.508)
			(layers "B.Cu" "B.Mask" "B.Paste")
			(net "P5V_AUX_ADC")
		)
		(pad "2" smd rect
			(at -0.40005 0)
			(size 0.4572 0.508)
			(layers "B.Cu" "B.Mask" "B.Paste")
			(net "P5V_AUX_ADC_TIC")
		)
	)
	(footprint ""
		(layer "B.Cu")
		(at 337.118706 -398.942052 90)
		(property "Reference" "C634"
			(at 0 0 90)
			(layer "B.SilkS")
			(hide yes)
			(effects
				(font
					(size 1.27 1.27)
				)
				(justify mirror)
			)
		)
		(property "Value" ""
			(at 0 0 90)
			(layer "B.Fab")
			(effects
				(font
					(size 1.27 1.27)
				)
				(justify mirror)
			)
		)
		(duplicate_pad_numbers_are_jumpers no)
		(fp_line
			(start 0.7874 -0.4064)
			(end -0.7874 -0.4064)
			(stroke
				(width 0.1524)
				(type default)
			)
			(layer "B.SilkS")
		)
		(fp_line
			(start -0.7874 -0.4064)
			(end -0.7874 0.4064)
			(stroke
				(width 0.1524)
				(type default)
			)
			(layer "B.SilkS")
		)
		(fp_line
			(start 0.7874 0.4064)
			(end 0.7874 -0.4064)
			(stroke
				(width 0.1524)
				(type default)
			)
			(layer "B.SilkS")
		)
		(fp_line
			(start -0.7874 0.4064)
			(end 0.7874 0.4064)
			(stroke
				(width 0.1524)
				(type default)
			)
			(layer "B.SilkS")
		)
		(fp_line
			(start 0.67945 -0.305054)
			(end 0.12065 -0.305054)
			(stroke
				(width 0.1)
				(type default)
			)
			(layer "B.Fab")
		)
		(fp_line
			(start 0.12065 -0.305054)
			(end 0.12065 -0.2794)
			(stroke
				(width 0.1)
				(type default)
			)
			(layer "B.Fab")
		)
		(fp_line
			(start -0.12065 -0.3048)
			(end -0.67945 -0.3048)
			(stroke
				(width 0.1)
				(type default)
			)
			(layer "B.Fab")
		)
		(fp_line
			(start -0.67945 -0.3048)
			(end -0.67945 0.3048)
			(stroke
				(width 0.1)
				(type default)
			)
			(layer "B.Fab")
		)
		(fp_line
			(start 0.12065 -0.2794)
			(end -0.12065 -0.2794)
			(stroke
				(width 0.1)
				(type default)
			)
			(layer "B.Fab")
		)
		(fp_line
			(start -0.12065 -0.2794)
			(end -0.12065 -0.3048)
			(stroke
				(width 0.1)
				(type default)
			)
			(layer "B.Fab")
		)
		(fp_line
			(start 0.12065 0.2794)
			(end 0.12065 0.3048)
			(stroke
				(width 0.1)
				(type default)
			)
			(layer "B.Fab")
		)
		(fp_line
			(start -0.120396 0.2794)
			(end 0.12065 0.2794)
			(stroke
				(width 0.1)
				(type default)
			)
			(layer "B.Fab")
		)
		(fp_line
			(start 0.67945 0.3048)
			(end 0.67945 -0.305054)
			(stroke
				(width 0.1)
				(type default)
			)
			(layer "B.Fab")
		)
		(fp_line
			(start 0.12065 0.3048)
			(end 0.67945 0.3048)
			(stroke
				(width 0.1)
				(type default)
			)
			(layer "B.Fab")
		)
		(fp_line
			(start -0.120396 0.3048)
			(end -0.120396 0.2794)
			(stroke
				(width 0.1)
				(type default)
			)
			(layer "B.Fab")
		)
		(fp_line
			(start -0.67945 0.3048)
			(end -0.120396 0.3048)
			(stroke
				(width 0.1)
				(type default)
			)
			(layer "B.Fab")
		)
		(pad "1" smd circle
			(at 0.40005 0 270)
			(size 0 0)
			(layers "B.Cu" "B.Mask" "B.Paste")
			(net "P0V9_CPU0_RT1_2A")
		)
		(pad "2" smd circle
			(at -0.40005 0 270)
			(size 0 0)
			(layers "B.Cu" "B.Mask" "B.Paste")
			(net "GND")
		)
	)
	(footprint ""
		(layer "B.Cu")
		(at 115.691158 -390.560052 90)
		(property "Reference" "C476"
			(at 0 0 90)
			(layer "B.SilkS")
			(hide yes)
			(effects
				(font
					(size 1.27 1.27)
				)
				(justify mirror)
			)
		)
		(property "Value" ""
			(at 0 0 90)
			(layer "B.Fab")
			(effects
				(font
					(size 1.27 1.27)
				)
				(justify mirror)
			)
		)
		(duplicate_pad_numbers_are_jumpers no)
		(fp_line
			(start 0.7874 -0.4064)
			(end -0.7874 -0.4064)
			(stroke
				(width 0.1524)
				(type default)
			)
			(layer "B.SilkS")
		)
		(fp_line
			(start -0.7874 -0.4064)
			(end -0.7874 0.4064)
			(stroke
				(width 0.1524)
				(type default)
			)
			(layer "B.SilkS")
		)
		(fp_line
			(start 0.7874 0.4064)
			(end 0.7874 -0.4064)
			(stroke
				(width 0.1524)
				(type default)
			)
			(layer "B.SilkS")
		)
		(fp_line
			(start -0.7874 0.4064)
			(end 0.7874 0.4064)
			(stroke
				(width 0.1524)
				(type default)
			)
			(layer "B.SilkS")
		)
		(fp_line
			(start 0.67945 -0.305054)
			(end 0.12065 -0.305054)
			(stroke
				(width 0.1)
				(type default)
			)
			(layer "B.Fab")
		)
		(fp_line
			(start 0.12065 -0.305054)
			(end 0.12065 -0.2794)
			(stroke
				(width 0.1)
				(type default)
			)
			(layer "B.Fab")
		)
		(fp_line
			(start -0.12065 -0.3048)
			(end -0.67945 -0.3048)
			(stroke
				(width 0.1)
				(type default)
			)
			(layer "B.Fab")
		)
		(fp_line
			(start -0.67945 -0.3048)
			(end -0.67945 0.3048)
			(stroke
				(width 0.1)
				(type default)
			)
			(layer "B.Fab")
		)
		(fp_line
			(start 0.12065 -0.2794)
			(end -0.12065 -0.2794)
			(stroke
				(width 0.1)
				(type default)
			)
			(layer "B.Fab")
		)
		(fp_line
			(start -0.12065 -0.2794)
			(end -0.12065 -0.3048)
			(stroke
				(width 0.1)
				(type default)
			)
			(layer "B.Fab")
		)
		(fp_line
			(start 0.12065 0.2794)
			(end 0.12065 0.3048)
			(stroke
				(width 0.1)
				(type default)
			)
			(layer "B.Fab")
		)
		(fp_line
			(start -0.120396 0.2794)
			(end 0.12065 0.2794)
			(stroke
				(width 0.1)
				(type default)
			)
			(layer "B.Fab")
		)
		(fp_line
			(start 0.67945 0.3048)
			(end 0.67945 -0.305054)
			(stroke
				(width 0.1)
				(type default)
			)
			(layer "B.Fab")
		)
		(fp_line
			(start 0.12065 0.3048)
			(end 0.67945 0.3048)
			(stroke
				(width 0.1)
				(type default)
			)
			(layer "B.Fab")
		)
		(fp_line
			(start -0.120396 0.3048)
			(end -0.120396 0.2794)
			(stroke
				(width 0.1)
				(type default)
			)
			(layer "B.Fab")
		)
		(fp_line
			(start -0.67945 0.3048)
			(end -0.120396 0.3048)
			(stroke
				(width 0.1)
				(type default)
			)
			(layer "B.Fab")
		)
		(pad "1" smd circle
			(at 0.40005 0 270)
			(size 0 0)
			(layers "B.Cu" "B.Mask" "B.Paste")
			(net "P0V9_CPU1_RT3_2A")
		)
		(pad "2" smd circle
			(at -0.40005 0 270)
			(size 0 0)
			(layers "B.Cu" "B.Mask" "B.Paste")
			(net "GND")
		)
	)
)
